# Bryce Canyon_Front_Drive_Plane_Board_Stackup.xlsx — Stack up_16315-1 (pcb-stackup)
|  |  |  |  |  | Version |  |  |  |  |  |  |  |  |  |  |  |  |  |  |  |  |  |  |  |
| Board Number: |  | 16315-1 |  |  | 02 |  |  |  |  |  |  |  |  |  |  |  |  |  |  |  |  |  |  |  |
| Project name: |  | Bryce Canyon |  |  |  |  |  |  |  |  |  |  |  |  |  |  |  |  |  |  |  |  |  |  |
| Model Name: |  | Front Drive Plane Board |  |  |  |  |  |  |  |  |  |  |  |  |  |  |  |  |  |  |  |  |  |  |
| Layer Count: |  | 12 Layer |  |  |  |  |  |  |  |  |  |  |  |  |  |  |  |  |  |  |  |  |  |  |
| Date: |  | 2017-09-25 00:00:00 |  |  |  |  |  |  |  |  |  |  |  |  |  |  |  |  |  |  |  |  |  |  |
| Low Loss Material: |  | TU863+VLP (Tg : 180/Td : 375) |  |  |  |  |  | Single Ended Type(mil) |  |  |  |  | Differential Type(mil) |  |  |  |  |  |  |  |  |  |  |  |
| Gold Finger(Y/N): |  | N |  |  |  |  | Imp | 50 |  |  |  | Imp | 85 |  |  |  |  |  | 100 |  |  |  |  |  |
| Customer: |  | <name> |  |  |  |  | Variation | Inner/Outer+/-5ohm |  |  |  | Variation | Inner/Outer+/-10% |  |  |  |  |  | Inner/Outer+/-10% |  |  |  |  |  |
| EE engineer |  | <name> |  |  |  |  | Bus | MISC. |  |  |  | Bus | PCIe / Clock |  |  |  |  |  | SATA |  |  |  |  |  |
| SI Engineer |  | <name> |  |  |  |  |  |  |  |  |  |  |  |  |  |  |  |  |  |  |  |  |  |  |
|  |  |  |  |  |  |  | Type | SE |  |  |  | Type | DP |  |  |  |  |  | DP |  |  |  |  |  |
| Layer |  |  | Thickness | Glass/Copper Style | Er | Df(1G) | Layers | 1,3,5,8,10,12 |  |  |  | Layers | 1,3,5,8,10,12 |  |  |  |  |  | 1,3,5,8,10,12 |  |  |  |  |  |
|  |  | Cu oz | Wiwynn |  | Wiwynn |  |  | Wiwynn |  |  |  |  | Wiwynn |  |  |  |  |  | Wiwynn |  |  |  |  |  |
|  | Mask |  | 0.5 |  | 3.4 | 0.025 |  | Width | Imp | Width | Imp |  | Width | Space | Imp | Width | Space | Imp | Width | Space | Imp | Width | Space | Imp |
| Top | Signal | 0.5 oz+plating | 2.1 |  |  |  | S1 | 6.75(L2) | 50.17 |  |  | S1 | 6.5(L2) | 5 | 84.97 |  |  |  | 5(L2) | 6.5 | 99.87 |  |  |  |
|  | Prepreg |  | 4 |  | 3.8 | 0.006 |  |  |  |  |  |  |  |  |  |  |  |  |  |  |  |  |  |  |
| L2 | GND | 1 oz | 1.3 |  |  |  | P2 | reference layer |  |  |  | P2 | reference layer |  |  |  |  |  | reference layer |  |  |  |  |  |
|  | Core |  | 5 |  | 3.8 | 0.006 |  |  |  |  |  |  |  |  |  |  |  |  |  |  |  |  |  |  |
| L3 | Signal | 1 oz | 1.3 |  |  |  | S3 | 5.25(L2/L4) | 49.65 |  |  | S3 | 5.5(L2/L4) | 6 | 85.19 |  |  |  | 4.25(L2/L4) | 8.75 | 99.77 |  |  |  |
|  | Prepreg |  | 9 |  | 4.2 | 0.006 |  |  |  |  |  |  |  |  |  |  |  |  |  |  |  |  |  |  |
| L4 | GND | 1 oz | 1.3 |  |  |  | P4 | reference layer |  |  |  | P4 | reference layer |  |  |  |  |  | reference layer |  |  |  |  |  |
|  | Core |  | 4 |  | 3.8 | 0.006 |  |  |  |  |  |  |  |  |  |  |  |  |  |  |  |  |  |  |
| L5 | Signal | 1 oz | 1.3 |  |  |  | S5 | 4.75(L4/L6) | 49.49 |  |  | S5 | 5(L4/L6) | 6 | 84.86 |  |  |  | 4(L4/L6) | 9 | 99.07 |  |  |  |
|  | Prepreg |  | 12 |  | 4.2 | 0.006 |  |  |  |  |  |  |  |  |  |  |  |  |  |  |  |  |  |  |
| L6 | POWER | 2 oz | 2.6 |  |  |  | P6 | reference layer |  |  |  | P6 | reference layer |  |  |  |  |  | reference layer |  |  |  |  |  |
|  | Core |  | 4 |  | 4 | 0.006 |  |  |  |  |  |  |  |  |  |  |  |  |  |  |  |  |  |  |
| L7 | POWER | 2 oz | 2.6 |  |  |  | P7 | reference layer |  |  |  | P7 | reference layer |  |  |  |  |  | reference layer |  |  |  |  |  |
|  | Prepreg |  | 12 |  | 4.2 | 0.006 |  |  |  |  |  |  |  |  |  |  |  |  |  |  |  |  |  |  |
| L8 | Signal | 1 oz | 1.3 |  |  |  | S8 | 4.75(L7/L9) | 49.49 |  |  | S8 | 5(L7/L9) | 6 | 84.86 |  |  |  | 4(L7/L9) | 9 | 99.07 |  |  |  |
|  | Core |  | 4 |  | 3.8 | 0.006 |  |  |  |  |  |  |  |  |  |  |  |  |  |  |  |  |  |  |
| L9 | GND | 1 oz | 1.3 |  |  |  | P9 | reference layer |  |  |  | P9 | reference layer |  |  |  |  |  | reference layer |  |  |  |  |  |
|  | Prepreg |  | 9 |  | 4.2 | 0.006 |  |  |  |  |  |  |  |  |  |  |  |  |  |  |  |  |  |  |
| L10 | Signal | 1 oz | 1.3 |  |  |  | S10 | 5.25(L9/L11) | 49.65 |  |  | S10 | 5.5(L9/L11) | 6 | 85.19 |  |  |  | 4.25(L9/L11) | 8.75 | 99.77 |  |  |  |
|  | Core |  | 5 |  | 3.8 | 0.006 |  |  |  |  |  |  |  |  |  |  |  |  |  |  |  |  |  |  |
| L11 | GND | 1 oz | 1.3 |  |  |  | P11 | reference layer |  |  |  | P11 | reference layer |  |  |  |  |  | reference layer |  |  |  |  |  |
|  | Prepreg |  | 4 |  | 3.8 | 0.006 |  |  |  |  |  |  |  |  |  |  |  |  |  |  |  |  |  |  |
| Bottom | Signal | 0.5 oz+plating | 2.1 |  |  |  | S12 | 6.75(L11) | 50.17 |  |  | S12 | 6.5(L11) | 5 | 84.97 |  |  |  | 5(L11) | 6.5 | 99.87 |  |  |  |
|  | Mask |  | 0.5 |  | 3.4 | 0.025 |  |  |  |  |  |  |  |  |  |  |  |  |  |  |  |  |  |  |
| Thickness requirement: 2.36 ± 10% mm |  | mil | 92.79999999999998 |  |  |  |  |  |  |  |  |  |  |  |  |  |  |  |  |  |  |  |  |  |
|  |  | mm | 2.3571247142494283 |  |  |  |  |  |  |  |  |  |  |  |  |  |  |  |  |  |  |  |  |  |
| Note: | 1. Unit is mil |  |  |  |  |  |  |  |  |  |  |  |  |  |  |  |  |  |  |  |  |  |  |  |
|  | 2. The total thickness includes trace and solder mask. |  |  |  |  |  |  |  |  |  |  |  |  |  |  |  |  |  |  |  |  |  |  |  |
|  | 3. Minimum hole copper thickness is 1.0 mil. |  |  |  |  |  |  |  |  |  |  |  |  |  |  |  |  |  |  |  |  |  |  |  |
|  | 4. Minimum surface copper thickness 1.5 mil. |  |  |  |  |  |  |  |  |  |  |  |  |  |  |  |  |  |  |  |  |  |  |  |
|  | 5. If there is no controlled impedance line described as the stackup in the gerber file, PCB supplier can ignore this kind of impedance control directly, but need to inform Wiwynn in engineering question(EQ). |  |  |  |  |  |  |  |  |  |  |  |  |  |  |  |  |  |  |  |  |  |  |  |
|  | 6. PCB test coupon requirement and PCB test note are described in the another sheets. |  |  |  |  |  |  |  |  |  |  |  |  |  |  |  |  |  |  |  |  |  |  |  |
|  | 7. If there is no "Delta-L" design in gerber file, PCB supplier should design 85 ohm "Delta-L" angle routing coupon and provide the measurement results in FAI report which meet the following criteria: |  |  |  |  |  |  |  |  |  |  |  |  |  |  |  |  |  |  |  |  |  |  |  |
|  | For low-loss material |  |  |  |  |  |  |  |  |  |  |  |  |  |  |  |  |  |  |  |  |  |  |  |
|  | (1)   0.55 dB/inch @ 4GHz; 1.05 dB/inch @ 8GHz for microstrip routing |  |  |  |  |  |  |  |  |  |  |  |  |  |  |  |  |  |  |  |  |  |  |  |
|  | (2)   0.48 dB/inch @ 4GHz; 0.9 dB/inch @ 8GHz for stripline routing |  |  |  |  |  |  |  |  |  |  |  |  |  |  |  |  |  |  |  |  |  |  |  |
